# S9S_MB_2U (Grand Teton) — schematic netlist excerpt (pin names and nets, part order shuffled) for the footprints in the layout excerpt that follows; sources: Cadence DE-HDL packaged netlist, KiCad conversion of 03242023_DA0F0TMBIJ0_F0T_Motherboard_J_brd_V01_OCP.brd

U195  74LVC2G17GW  IC  pkg SOT363  page 151
  A0  = BMC_MONITER_R
  GND  = GND
  A1  = RST_SWB_BIC_R_N
  B1  = RST_SWB_BIC_BUF_R_N
  VCC  = P3V3_AUX
  B0  = BMC_MONITER_BUF_R

PC2262  Q_CAP  22UF 16V 20% X6S  pkg C0805  page 259 : A = SW_P3V3_AUX_FLT ; B = GND

(kicad_pcb
	(version 20260206)
	(generator "pcbnew")
	(generator_version "10.0")
	(general
		(thickness 1.6)
		(legacy_teardrops no)
	)
	(paper "A4")
	(title_block
		(title "03242023_DA0F0TMBIJ0_F0T_Motherboard_J_brd_V01_OCP.brd")
		(comment 1 "Grand Teton / footprints 3692-3693 of 6105")
	)
	(layers
		(0 "F.Cu" signal "TOP")
		(4 "In1.Cu" signal "GND")
		(6 "In2.Cu" signal "IN1")
		(8 "In3.Cu" signal "GND1")
		(10 "In4.Cu" signal "IN2")
		(12 "In5.Cu" signal "GND2")
		(14 "In6.Cu" signal "IN3")
		(16 "In7.Cu" signal "GND3")
		(18 "In8.Cu" signal "VCC")
		(20 "In9.Cu" signal "VCC1")
		(22 "In10.Cu" signal "GND4")
		(24 "In11.Cu" signal "IN4")
		(26 "In12.Cu" signal "GND5")
		(28 "In13.Cu" signal "IN5")
		(30 "In14.Cu" signal "GND6")
		(32 "In15.Cu" signal "IN6")
		(34 "In16.Cu" signal "GND7")
		(2 "B.Cu" signal "BOTTOM")
		(9 "F.Adhes" user "F.Adhesive")
		(11 "B.Adhes" user "B.Adhesive")
		(13 "F.Paste" user "Package Geometry/Pastemask Top")
		(15 "B.Paste" user "Package Geometry/Pastemask Bottom")
		(5 "F.SilkS" user "Ref Des/Silkscreen Top")
		(7 "B.SilkS" user "Ref Des/Silkscreen Bottom")
		(1 "F.Mask" user "Board Geometry/Soldermask Top")
		(3 "B.Mask" user "Board Geometry/Soldermask Bottom")
		(17 "Dwgs.User" user "User.Drawings")
		(19 "Cmts.User" user "User.Comments")
		(21 "Eco1.User" user "User.Eco1")
		(23 "Eco2.User" user "User.Eco2")
		(25 "Edge.Cuts" user "Board Geometry/Outline")
		(27 "Margin" user)
		(31 "F.CrtYd" user "Package Geometry/Place Bound Top")
		(29 "B.CrtYd" user "Package Geometry/Place Bound Bottom")
		(35 "F.Fab" user "Ref Des/Assembly Top")
		(33 "B.Fab" user "Ref Des/Assembly Bottom")
	)
	(footprint ""
		(layer "F.Cu")
		(at 172.36948 -424.398948)
		(property "Reference" "U195"
			(at -1.41478 -2.86639 0)
			(unlocked yes)
			(layer "F.SilkS")
			(effects
				(font
					(size 0.7874 0.5842)
					(thickness 0.1524)
				)
				(justify left)
			)
		)
		(property "Value" ""
			(at 0 0 0)
			(layer "F.Fab")
			(effects
				(font
					(size 1.27 1.27)
				)
			)
		)
		(duplicate_pad_numbers_are_jumpers no)
		(fp_line
			(start -1.3462 -1.100074)
			(end -0.670052 -1.100074)
			(stroke
				(width 0.1524)
				(type default)
			)
			(layer "F.SilkS")
		)
		(fp_line
			(start -1.3462 1.100074)
			(end -1.3462 -1.100074)
			(stroke
				(width 0.1524)
				(type default)
			)
			(layer "F.SilkS")
		)
		(fp_line
			(start -0.670052 -1.100074)
			(end 0 -0.381)
			(stroke
				(width 0.1524)
				(type default)
			)
			(layer "F.SilkS")
		)
		(fp_line
			(start 0 -0.381)
			(end 0.670052 -1.100074)
			(stroke
				(width 0.1524)
				(type default)
			)
			(layer "F.SilkS")
		)
		(fp_line
			(start 0.670052 -1.100074)
			(end 1.3462 -1.100074)
			(stroke
				(width 0.1524)
				(type default)
			)
			(layer "F.SilkS")
		)
		(fp_line
			(start 1.3462 -1.100074)
			(end 1.3462 1.100074)
			(stroke
				(width 0.1524)
				(type default)
			)
			(layer "F.SilkS")
		)
		(fp_line
			(start 1.3462 1.100074)
			(end -1.3462 1.100074)
			(stroke
				(width 0.1524)
				(type default)
			)
			(layer "F.SilkS")
		)
		(fp_poly
			(pts
				(xy -1.049274 -1.31826) (xy -1.430274 -2.08026) (xy -0.668274 -2.08026)
			)
			(stroke
				(width 0)
				(type default)
			)
			(fill yes)
			(layer "F.SilkS")
		)
		(fp_line
			(start -1.100074 -0.8001)
			(end -0.670052 -0.8001)
			(stroke
				(width 0.1)
				(type default)
			)
			(layer "F.Fab")
		)
		(fp_line
			(start -1.100074 0.8001)
			(end -1.100074 -0.8001)
			(stroke
				(width 0.1)
				(type default)
			)
			(layer "F.Fab")
		)
		(fp_line
			(start -0.670052 -1.100074)
			(end 0.670052 -1.100074)
			(stroke
				(width 0.1)
				(type default)
			)
			(layer "F.Fab")
		)
		(fp_line
			(start -0.670052 -0.8001)
			(end -0.670052 -1.100074)
			(stroke
				(width 0.1)
				(type default)
			)
			(layer "F.Fab")
		)
		(fp_line
			(start -0.670052 0.8001)
			(end -1.100074 0.8001)
			(stroke
				(width 0.1)
				(type default)
			)
			(layer "F.Fab")
		)
		(fp_line
			(start -0.670052 0.8001)
			(end -0.670052 -0.8001)
			(stroke
				(width 0.1)
				(type default)
			)
			(layer "F.Fab")
		)
		(fp_line
			(start -0.670052 1.100074)
			(end -0.670052 0.8001)
			(stroke
				(width 0.1)
				(type default)
			)
			(layer "F.Fab")
		)
		(fp_line
			(start 0.670052 -1.100074)
			(end 0.670052 -0.8001)
			(stroke
				(width 0.1)
				(type default)
			)
			(layer "F.Fab")
		)
		(fp_line
			(start 0.670052 -0.8001)
			(end 0.670052 0.8001)
			(stroke
				(width 0.1)
				(type default)
			)
			(layer "F.Fab")
		)
		(fp_line
			(start 0.670052 -0.8001)
			(end 1.100074 -0.8001)
			(stroke
				(width 0.1)
				(type default)
			)
			(layer "F.Fab")
		)
		(fp_line
			(start 0.670052 0.8001)
			(end 0.670052 1.100074)
			(stroke
				(width 0.1)
				(type default)
			)
			(layer "F.Fab")
		)
		(fp_line
			(start 0.670052 1.100074)
			(end -0.670052 1.100074)
			(stroke
				(width 0.1)
				(type default)
			)
			(layer "F.Fab")
		)
		(fp_line
			(start 1.100074 -0.8001)
			(end 1.100074 0.8001)
			(stroke
				(width 0.1)
				(type default)
			)
			(layer "F.Fab")
		)
		(fp_line
			(start 1.100074 0.8001)
			(end 0.670052 0.8001)
			(stroke
				(width 0.1)
				(type default)
			)
			(layer "F.Fab")
		)
		(fp_poly
			(pts
				(xy -1.524 -0.649986) (xy -2.286 -1.030986) (xy -2.286 -0.268986)
			)
			(stroke
				(width 0)
				(type default)
			)
			(fill yes)
			(layer "F.Fab")
		)
		(pad "1" smd rect
			(at -0.94996 -0.649986 270)
			(size 0.4064 0.508)
			(layers "F.Cu" "F.Mask" "F.Paste")
			(net "BMC_MONITER_R")
		)
		(pad "2" smd rect
			(at -0.94996 0 270)
			(size 0.4064 0.508)
			(layers "F.Cu" "F.Mask" "F.Paste")
			(net "GND")
		)
		(pad "3" smd rect
			(at -0.94996 0.649986 270)
			(size 0.4064 0.508)
			(layers "F.Cu" "F.Mask" "F.Paste")
			(net "RST_SWB_BIC_R_N")
		)
		(pad "4" smd rect
			(at 0.94996 0.649986 270)
			(size 0.4064 0.508)
			(layers "F.Cu" "F.Mask" "F.Paste")
			(net "RST_SWB_BIC_BUF_R_N")
		)
		(pad "5" smd rect
			(at 0.94996 0 270)
			(size 0.4064 0.508)
			(layers "F.Cu" "F.Mask" "F.Paste")
			(net "P3V3_AUX")
		)
		(pad "6" smd rect
			(at 0.94996 -0.649986 270)
			(size 0.4064 0.508)
			(layers "F.Cu" "F.Mask" "F.Paste")
			(net "BMC_MONITER_BUF_R")
		)
	)
	(footprint ""
		(layer "F.Cu")
		(at 460.092044 -76.57211 90)
		(property "Reference" "PC2262"
			(at 0 0 90)
			(layer "F.SilkS")
			(hide yes)
			(effects
				(font
					(size 1.27 1.27)
				)
			)
		)
		(property "Value" ""
			(at 0 0 90)
			(layer "F.Fab")
			(effects
				(font
					(size 1.27 1.27)
				)
			)
		)
		(duplicate_pad_numbers_are_jumpers no)
		(fp_line
			(start 1.524 -0.762)
			(end 1.524 0.762)
			(stroke
				(width 0.1524)
				(type default)
			)
			(layer "F.SilkS")
		)
		(fp_line
			(start -1.524 -0.762)
			(end 1.524 -0.762)
			(stroke
				(width 0.1524)
				(type default)
			)
			(layer "F.SilkS")
		)
		(fp_line
			(start 1.524 0.762)
			(end -1.524 0.762)
			(stroke
				(width 0.1524)
				(type default)
			)
			(layer "F.SilkS")
		)
		(fp_line
			(start -1.524 0.762)
			(end -1.524 -0.762)
			(stroke
				(width 0.1524)
				(type default)
			)
			(layer "F.SilkS")
		)
		(fp_line
			(start 1.1049 -0.724916)
			(end -1.1049 -0.724916)
			(stroke
				(width 0.1)
				(type default)
			)
			(layer "F.Fab")
		)
		(fp_line
			(start -1.1049 -0.724916)
			(end -1.1049 0.724916)
			(stroke
				(width 0.1)
				(type default)
			)
			(layer "F.Fab")
		)
		(fp_line
			(start 1.1049 0.724916)
			(end 1.1049 -0.724916)
			(stroke
				(width 0.1)
				(type default)
			)
			(layer "F.Fab")
		)
		(fp_line
			(start -1.1049 0.724916)
			(end 1.1049 0.724916)
			(stroke
				(width 0.1)
				(type default)
			)
			(layer "F.Fab")
		)
		(pad "1" smd rect
			(at -0.889 0 270)
			(size 1.016 1.27)
			(layers "F.Cu" "F.Mask" "F.Paste")
			(net "SW_P3V3_AUX_FLT")
		)
		(pad "2" smd rect
			(at 0.889 0 270)
			(size 1.016 1.27)
			(layers "F.Cu" "F.Mask" "F.Paste")
			(net "GND")
		)
	)
)
